# SCM (Grand Teton) — schematic netlist excerpt (pin names and nets, part order shuffled) for the footprints in the layout excerpt that follows; sources: Cadence DE-HDL packaged netlist, KiCad conversion of 12092022_DA0F0TMDCD0_F0T_Management_Board_D_brd_V3_OCP.brd

R422  Q_RES  2.2K 5% CHIP  pkg 0402LF  page 27 : A = P3V3_AUX ; B = SMB_BMC_MM13_SCL
R546  Q_RES  0 5% CHIP  pkg 0402LF  page 31 : A = SPA_SOUT_SW_DBG ; B = SPA_SOUT_SW_DBG_R

(kicad_pcb
	(version 20260206)
	(generator "pcbnew")
	(generator_version "10.0")
	(general
		(thickness 1.6)
		(legacy_teardrops no)
	)
	(paper "A4")
	(title_block
		(title "12092022_DA0F0TMDCD0_F0T_Management_Board_D_brd_V3_OCP.brd")
		(comment 1 "Grand Teton / footprints 1402-1403 of 1440")
	)
	(layers
		(0 "F.Cu" signal "TOP")
		(4 "In1.Cu" signal "GND")
		(6 "In2.Cu" signal "IN1")
		(8 "In3.Cu" signal "GND1")
		(10 "In4.Cu" signal "IN2")
		(12 "In5.Cu" signal "VCC")
		(14 "In6.Cu" signal "VCC1")
		(16 "In7.Cu" signal "IN3")
		(18 "In8.Cu" signal "GND2")
		(20 "In9.Cu" signal "IN4")
		(22 "In10.Cu" signal "GND3")
		(2 "B.Cu" signal "BOTTOM")
		(9 "F.Adhes" user "F.Adhesive")
		(11 "B.Adhes" user "B.Adhesive")
		(13 "F.Paste" user "Package Geometry/Pastemask Top")
		(15 "B.Paste" user "Package Geometry/Pastemask Bottom")
		(5 "F.SilkS" user "Ref Des/Silkscreen Top")
		(7 "B.SilkS" user "Ref Des/Silkscreen Bottom")
		(1 "F.Mask" user "Board Geometry/Soldermask Top")
		(3 "B.Mask" user "Board Geometry/Soldermask Bottom")
		(17 "Dwgs.User" user "User.Drawings")
		(19 "Cmts.User" user "User.Comments")
		(21 "Eco1.User" user "User.Eco1")
		(23 "Eco2.User" user "User.Eco2")
		(25 "Edge.Cuts" user "Board Geometry/Outline")
		(27 "Margin" user)
		(31 "F.CrtYd" user "Package Geometry/Place Bound Top")
		(29 "B.CrtYd" user "Package Geometry/Place Bound Bottom")
		(35 "F.Fab" user "Ref Des/Assembly Top")
		(33 "B.Fab" user "Ref Des/Assembly Bottom")
	)
	(footprint ""
		(layer "B.Cu")
		(at 32.4612 -63.4238 180)
		(property "Reference" "R546"
			(at 0 0 0)
			(layer "B.SilkS")
			(hide yes)
			(effects
				(font
					(size 1.27 1.27)
				)
				(justify mirror)
			)
		)
		(property "Value" ""
			(at 0 0 0)
			(layer "B.Fab")
			(effects
				(font
					(size 1.27 1.27)
				)
				(justify mirror)
			)
		)
		(duplicate_pad_numbers_are_jumpers no)
		(fp_line
			(start 0.7874 0.4064)
			(end 0.7874 -0.4064)
			(stroke
				(width 0.1524)
				(type default)
			)
			(layer "B.SilkS")
		)
		(fp_line
			(start 0.7874 -0.4064)
			(end -0.7874 -0.4064)
			(stroke
				(width 0.1524)
				(type default)
			)
			(layer "B.SilkS")
		)
		(fp_line
			(start -0.7874 0.4064)
			(end 0.7874 0.4064)
			(stroke
				(width 0.1524)
				(type default)
			)
			(layer "B.SilkS")
		)
		(fp_line
			(start -0.7874 -0.4064)
			(end -0.7874 0.4064)
			(stroke
				(width 0.1524)
				(type default)
			)
			(layer "B.SilkS")
		)
		(fp_line
			(start 0.67945 0.3048)
			(end 0.67945 -0.305054)
			(stroke
				(width 0.1)
				(type default)
			)
			(layer "B.Fab")
		)
		(fp_line
			(start 0.67945 -0.305054)
			(end 0.12065 -0.305054)
			(stroke
				(width 0.1)
				(type default)
			)
			(layer "B.Fab")
		)
		(fp_line
			(start 0.12065 0.3048)
			(end 0.67945 0.3048)
			(stroke
				(width 0.1)
				(type default)
			)
			(layer "B.Fab")
		)
		(fp_line
			(start 0.12065 0.2794)
			(end 0.12065 0.3048)
			(stroke
				(width 0.1)
				(type default)
			)
			(layer "B.Fab")
		)
		(fp_line
			(start 0.12065 -0.2794)
			(end -0.12065 -0.2794)
			(stroke
				(width 0.1)
				(type default)
			)
			(layer "B.Fab")
		)
		(fp_line
			(start 0.12065 -0.305054)
			(end 0.12065 -0.2794)
			(stroke
				(width 0.1)
				(type default)
			)
			(layer "B.Fab")
		)
		(fp_line
			(start -0.120396 0.3048)
			(end -0.120396 0.2794)
			(stroke
				(width 0.1)
				(type default)
			)
			(layer "B.Fab")
		)
		(fp_line
			(start -0.120396 0.2794)
			(end 0.12065 0.2794)
			(stroke
				(width 0.1)
				(type default)
			)
			(layer "B.Fab")
		)
		(fp_line
			(start -0.12065 -0.2794)
			(end -0.12065 -0.3048)
			(stroke
				(width 0.1)
				(type default)
			)
			(layer "B.Fab")
		)
		(fp_line
			(start -0.12065 -0.3048)
			(end -0.67945 -0.3048)
			(stroke
				(width 0.1)
				(type default)
			)
			(layer "B.Fab")
		)
		(fp_line
			(start -0.67945 0.3048)
			(end -0.120396 0.3048)
			(stroke
				(width 0.1)
				(type default)
			)
			(layer "B.Fab")
		)
		(fp_line
			(start -0.67945 -0.3048)
			(end -0.67945 0.3048)
			(stroke
				(width 0.1)
				(type default)
			)
			(layer "B.Fab")
		)
		(pad "1" smd circle
			(at 0.40005 0)
			(size 0 0)
			(layers "B.Cu" "B.Mask" "B.Paste")
			(net "SPA_SOUT_SW_DBG")
		)
		(pad "2" smd circle
			(at -0.40005 0)
			(size 0 0)
			(layers "B.Cu" "B.Mask" "B.Paste")
			(net "SPA_SOUT_SW_DBG_R")
		)
	)
	(footprint ""
		(layer "B.Cu")
		(at 39.37508 -44.63288)
		(property "Reference" "R422"
			(at 0 0 0)
			(layer "B.SilkS")
			(hide yes)
			(effects
				(font
					(size 1.27 1.27)
				)
				(justify mirror)
			)
		)
		(property "Value" ""
			(at 0 0 0)
			(layer "B.Fab")
			(effects
				(font
					(size 1.27 1.27)
				)
				(justify mirror)
			)
		)
		(duplicate_pad_numbers_are_jumpers no)
		(fp_line
			(start -0.7874 -0.4064)
			(end -0.7874 0.4064)
			(stroke
				(width 0.1524)
				(type default)
			)
			(layer "B.SilkS")
		)
		(fp_line
			(start -0.7874 0.4064)
			(end 0.7874 0.4064)
			(stroke
				(width 0.1524)
				(type default)
			)
			(layer "B.SilkS")
		)
		(fp_line
			(start 0.7874 -0.4064)
			(end -0.7874 -0.4064)
			(stroke
				(width 0.1524)
				(type default)
			)
			(layer "B.SilkS")
		)
		(fp_line
			(start 0.7874 0.4064)
			(end 0.7874 -0.4064)
			(stroke
				(width 0.1524)
				(type default)
			)
			(layer "B.SilkS")
		)
		(fp_line
			(start -0.67945 -0.3048)
			(end -0.67945 0.3048)
			(stroke
				(width 0.1)
				(type default)
			)
			(layer "B.Fab")
		)
		(fp_line
			(start -0.67945 0.3048)
			(end -0.120396 0.3048)
			(stroke
				(width 0.1)
				(type default)
			)
			(layer "B.Fab")
		)
		(fp_line
			(start -0.12065 -0.3048)
			(end -0.67945 -0.3048)
			(stroke
				(width 0.1)
				(type default)
			)
			(layer "B.Fab")
		)
		(fp_line
			(start -0.12065 -0.2794)
			(end -0.12065 -0.3048)
			(stroke
				(width 0.1)
				(type default)
			)
			(layer "B.Fab")
		)
		(fp_line
			(start -0.120396 0.2794)
			(end 0.12065 0.2794)
			(stroke
				(width 0.1)
				(type default)
			)
			(layer "B.Fab")
		)
		(fp_line
			(start -0.120396 0.3048)
			(end -0.120396 0.2794)
			(stroke
				(width 0.1)
				(type default)
			)
			(layer "B.Fab")
		)
		(fp_line
			(start 0.12065 -0.305054)
			(end 0.12065 -0.2794)
			(stroke
				(width 0.1)
				(type default)
			)
			(layer "B.Fab")
		)
		(fp_line
			(start 0.12065 -0.2794)
			(end -0.12065 -0.2794)
			(stroke
				(width 0.1)
				(type default)
			)
			(layer "B.Fab")
		)
		(fp_line
			(start 0.12065 0.2794)
			(end 0.12065 0.3048)
			(stroke
				(width 0.1)
				(type default)
			)
			(layer "B.Fab")
		)
		(fp_line
			(start 0.12065 0.3048)
			(end 0.67945 0.3048)
			(stroke
				(width 0.1)
				(type default)
			)
			(layer "B.Fab")
		)
		(fp_line
			(start 0.67945 -0.305054)
			(end 0.12065 -0.305054)
			(stroke
				(width 0.1)
				(type default)
			)
			(layer "B.Fab")
		)
		(fp_line
			(start 0.67945 0.3048)
			(end 0.67945 -0.305054)
			(stroke
				(width 0.1)
				(type default)
			)
			(layer "B.Fab")
		)
		(pad "1" smd circle
			(at 0.40005 0 180)
			(size 0 0)
			(layers "B.Cu" "B.Mask" "B.Paste")
			(net "P3V3_AUX")
		)
		(pad "2" smd circle
			(at -0.40005 0 180)
			(size 0 0)
			(layers "B.Cu" "B.Mask" "B.Paste")
			(net "SMB_BMC_MM13_SCL")
		)
	)
)
